# S9S_MB_2U (Grand Teton) — schematic netlist excerpt (pin names and nets, part order shuffled) for the footprints in the layout excerpt that follows; sources: Cadence DE-HDL packaged netlist, KiCad conversion of 03242023_DA0F0TMBIJ0_F0T_Motherboard_J_brd_V01_OCP.brd

J21  SCONN288_ADR50017P130CC  SCONN288_ADR50017-P130CC IO  pkg DDR288S_1-1VXB  page 102
  VIN_BULK0  = P12V_S3_AUX_CPU1_NVDIMM
  RFU0  = TP_CHC_CPU1_DIMM1_FRU_0
  VIN_MGMT  = P3V3_AUX
  HSCL  = I3C_SPD_DDRABCD_CPU1_LVC1_SCL_4
  HSDA  = I3C_SPD_DDRABCD_CPU1_LVC1_SDA
  VSS0  = GND
  DQ0_A  = M_C_CPU1_SA_DQ<0>
  VSS1  = GND
  DQ1_A  = M_C_CPU1_SA_DQ<1>
  VSS2  = GND
  DQS0_A_T  = M_C_CPU1_SA_DQS_DP<0>
  DQS0_A_C  = M_C_CPU1_SA_DQS_DN<0>
  VSS3  = GND
  DQ4_A  = M_C_CPU1_SA_DQ<4>
  VSS4  = GND
  DQ5_A  = M_C_CPU1_SA_DQ<5>
  VSS5  = GND
  DQ8_A  = M_C_CPU1_SA_DQ<8>
  VSS6  = GND
  DQ9_A  = M_C_CPU1_SA_DQ<9>
  VSS7  = GND
  DQS1_A_T  = M_C_CPU1_SA_DQS_DP<1>
  DQS1_A_C  = M_C_CPU1_SA_DQS_DN<1>
  VSS8  = GND
  DQ12_A  = M_C_CPU1_SA_DQ<12>
  VSS9  = GND
  DQ13_A  = M_C_CPU1_SA_DQ<13>
  VSS10  = GND
  DQ16_A  = M_C_CPU1_SA_DQ<16>
  VSS11  = GND
  DQ17_A  = M_C_CPU1_SA_DQ<17>
  VSS12  = GND
  DQS2_A_T  = M_C_CPU1_SA_DQS_DP<2>
  DQS2_A_C  = M_C_CPU1_SA_DQS_DN<2>
  VSS13  = GND
  DQ20_A  = M_C_CPU1_SA_DQ<20>
  VSS14  = GND
  DQ21_A  = M_C_CPU1_SA_DQ<21>
  VSS15  = GND
  DQ24_A  = M_C_CPU1_SA_DQ<24>
  VSS16  = GND
  DQ25_A  = M_C_CPU1_SA_DQ<25>
  VSS17  = GND
  DQS3_A_T  = M_C_CPU1_SA_DQS_DP<3>
  DQS3_A_C  = M_C_CPU1_SA_DQS_DN<3>
  VSS18  = GND
  DQ28_A  = M_C_CPU1_SA_DQ<28>
  VSS19  = GND
  DQ29_A  = M_C_CPU1_SA_DQ<29>
  VSS20  = GND
  CB0_A  = M_C_CPU1_SA_CB<0>
  VSS21  = GND
  CB1_A  = M_C_CPU1_SA_CB<1>
  VSS22  = GND
  DQS4_A_T  = M_C_CPU1_SA_DQS_DP<4>
  DQS4_A_C  = M_C_CPU1_SA_DQS_DN<4>
  VSS23  = GND
  CB4_A  = M_C_CPU1_SA_CB<4>
  VSS24  = GND
  CB5_A  = M_C_CPU1_SA_CB<5>
  VSS25  = GND
  ALERT_N  = M_C_CPU1_ALERT_N
  VSS26  = GND
  CS0_A_N  = M_C_CPU1_SA_CS_N<0>
  VSS27  = GND
  CA0_A  = M_C_CPU1_SA_CA<0>
  VSS28  = GND
  CA2_A  = M_C_CPU1_SA_CA<2>
  VSS29  = GND
  CA4_A  = M_C_CPU1_SA_CA<4>
  VSS30  = GND
  CA6_A  = M_C_CPU1_SA_CA<6>
  VSS31  = GND
  PAR_A  = M_C_CPU1_SA_PAR
  VSS32  = GND
  CA0_B  = M_C_CPU1_SB_CA<0>
  VSS33  = GND
  CA2_B  = M_C_CPU1_SB_CA<2>
  VSS34  = GND
  CA4_B  = M_C_CPU1_SB_CA<4>
  VSS35  = GND
  CA6_B  = M_C_CPU1_SB_CA<6>
  VSS36  = GND
  CS0_B_N  = M_C_CPU1_SB_CS_N<0>
  VSS37  = GND
  \lbd||rsp_a_n\  = M_C_CPU1_SA_RSP<0>
  \lbs||rsp_b_n\  = M_C_CPU1_SB_RSP<0>
  VSS38  = GND
  CB4_B  = M_C_CPU1_SB_CB<4>
  VSS39  = GND
  CB5_B  = M_C_CPU1_SB_CB<5>
  VSS40  = GND
  \dqs9_b_t||tdqs9_b_t||dbi4_b_n\  = M_C_CPU1_SB_DQS_DP<9>
  \dqs9_b_c||tdqs9_b_c\  = M_C_CPU1_SB_DQS_DN<9>
  VSS41  = GND
  CB0_B  = M_C_CPU1_SB_CB<0>
  VSS42  = GND
  CB1_B  = M_C_CPU1_SB_CB<1>
  VSS43  = GND
  DQ0_B  = M_C_CPU1_SB_DQ<0>
  VSS44  = GND
  DQ1_B  = M_C_CPU1_SB_DQ<1>
  VSS45  = GND
  DQS0_B_T  = M_C_CPU1_SB_DQS_DP<0>
  DQS0_B_C  = M_C_CPU1_SB_DQS_DN<0>
  VSS46  = GND
  DQ4_B  = M_C_CPU1_SB_DQ<4>
  VSS47  = GND
  DQ5_B  = M_C_CPU1_SB_DQ<5>
  VSS48  = GND
  DQ8_B  = M_C_CPU1_SB_DQ<8>
  VSS49  = GND
  DQ9_B  = M_C_CPU1_SB_DQ<9>
  VSS50  = GND
  DQS1_B_T  = M_C_CPU1_SB_DQS_DP<1>
  DQS1_B_C  = M_C_CPU1_SB_DQS_DN<1>
  VSS51  = GND
  DQ12_B  = M_C_CPU1_SB_DQ<12>
  VSS52  = GND
  DQ13_B  = M_C_CPU1_SB_DQ<13>
  VSS53  = GND
  DQ16_B  = M_C_CPU1_SB_DQ<16>
  VSS54  = GND
  DQ17_B  = M_C_CPU1_SB_DQ<17>
  VSS55  = GND
  DQS2_B_T  = M_C_CPU1_SB_DQS_DP<2>
  DQS2_B_C  = M_C_CPU1_SB_DQS_DN<2>
  VSS56  = GND
  DQ20_B  = M_C_CPU1_SB_DQ<20>
  VSS57  = GND
  DQ21_B  = M_C_CPU1_SB_DQ<21>
  VSS58  = GND
  DQ24_B  = M_C_CPU1_SB_DQ<24>
  VSS59  = GND
  DQ25_B  = M_C_CPU1_SB_DQ<25>
  VSS60  = GND
  DQS3_B_T  = M_C_CPU1_SB_DQS_DP<3>
  DQS3_B_C  = M_C_CPU1_SB_DQS_DN<3>
  VSS61  = GND
  DQ28_B  = M_C_CPU1_SB_DQ<28>
  VSS62  = GND
  DQ29_B  = M_C_CPU1_SB_DQ<29>
  VSS63  = GND
  RFU1  = TP_CHC_CPU1_DIMM1_FRU_1
  VIN_BULK1  = P12V_S3_AUX_CPU1_NVDIMM
  VIN_BULK2  = P12V_S3_AUX_CPU1_NVDIMM
  \pwr_good||fail_n\  = PWRGD_CHC_CPU1_DIMM1
  HSA  = PD_CHC_CPU1_DIMM1_SAA
  RFU2  = TP_CHC_CPU1_DIMM1_FRU_2
  RFU3  = TP_CHC_CPU1_DIMM1_FRU_3
  VSS64  = GND
  DQ2_A  = M_C_CPU1_SA_DQ<2>
  VSS65  = GND
  DQ3_A  = M_C_CPU1_SA_DQ<3>
  VSS66  = GND
  \dqs5_a_c||tdqs5_a_c||dqs5_a_t||tdqs5_a_t\  = M_C_CPU1_SA_DQS_DN<5>
  \dqs5_a_t||tdqs5_a_t\  = M_C_CPU1_SA_DQS_DP<5>
  VSS67  = GND
  DQ6_A  = M_C_CPU1_SA_DQ<6>
  VSS68  = GND
  DQ7_A  = M_C_CPU1_SA_DQ<7>
  VSS69  = GND
  DQ10_A  = M_C_CPU1_SA_DQ<10>
  VSS70  = GND
  DQ11_A  = M_C_CPU1_SA_DQ<11>
  VSS71  = GND
  \dqs6_a_c||tdqs6_a_c||dqs6_a_t||tdqs6_a_t\  = M_C_CPU1_SA_DQS_DN<6>
  \dqs6_a_t||tdqs6_a_t\  = M_C_CPU1_SA_DQS_DP<6>
  VSS72  = GND
  DQ14_A  = M_C_CPU1_SA_DQ<14>
  VSS73  = GND
  DQ15_A  = M_C_CPU1_SA_DQ<15>
  VSS74  = GND
  DQ18_A  = M_C_CPU1_SA_DQ<18>
  VSS75  = GND
  DQ19_A  = M_C_CPU1_SA_DQ<19>
  VSS76  = GND
  \dqs7_a_c||tdqs7_a_c\  = M_C_CPU1_SA_DQS_DN<7>
  \dqs7_a_t||tdqs7_a_t\  = M_C_CPU1_SA_DQS_DP<7>
  VSS77  = GND
  DQ22_A  = M_C_CPU1_SA_DQ<22>
  VSS78  = GND
  DQ23_A  = M_C_CPU1_SA_DQ<23>
  VSS79  = GND
  DQ26_A  = M_C_CPU1_SA_DQ<26>
  VSS80  = GND
  DQ27_A  = M_C_CPU1_SA_DQ<27>
  VSS81  = GND
  \dqs8_a_c||tdqs8_a_c\  = M_C_CPU1_SA_DQS_DN<8>
  \dqs8_a_t||tdqs8_a_t\  = M_C_CPU1_SA_DQS_DP<8>
  VSS82  = GND
  DQ30_A  = M_C_CPU1_SA_DQ<30>
  VSS83  = GND
  DQ31_A  = M_C_CPU1_SA_DQ<31>
  VSS84  = GND
  CB2_A  = M_C_CPU1_SA_CB<2>
  VSS85  = GND
  CB3_A  = M_C_CPU1_SA_CB<3>
  VSS86  = GND
  \dqs9_a_c||tdqs9_a_c\  = M_C_CPU1_SA_DQS_DN<9>
  \dqs9_a_t||tdqs9_a_t\  = M_C_CPU1_SA_DQS_DP<9>
  VSS87  = GND
  CB6_A  = M_C_CPU1_SA_CB<6>
  VSS88  = GND
  CB7_A  = M_C_CPU1_SA_CB<7>
  VSS89  = GND
  RESET_N  = RST_M_CD_CPU1_FPGA_N
  VSS90  = GND
  CS1_A_N  = M_C_CPU1_SA_CS_N<1>
  VSS91  = GND
  CA1_A  = M_C_CPU1_SA_CA<1>
  VSS92  = GND
  CA3_A  = M_C_CPU1_SA_CA<3>
  VSS93  = GND
  CA5_A  = M_C_CPU1_SA_CA<5>
  VSS94  = GND
  CK_T  = M_C_CPU1_CLK_DP<0>
  CK_C  = M_C_CPU1_CLK_DN<0>
  VSS95  = GND
  RFU4  = TP_CHC_CPU1_DIMM1_FRU_4
  CA1_B  = M_C_CPU1_SB_CA<1>
  VSS96  = GND
  CA3_B  = M_C_CPU1_SB_CA<3>
  VSS97  = GND
  CA5_B  = M_C_CPU1_SB_CA<5>
  VSS98  = GND
  PAR_B  = M_C_CPU1_SB_PAR
  VSS99  = GND
  CS1_B_N  = M_C_CPU1_SB_CS_N<1>
  VSS100  = GND
  RFU5  = TP_CHC_CPU1_DIMM1_FRU_5
  RFU6  = TP_CHC_CPU1_DIMM1_FRU_6
  VSS101  = GND
  CB6_B  = M_C_CPU1_SB_CB<6>
  VSS102  = GND
  CB7_B  = M_C_CPU1_SB_CB<7>
  VSS103  = GND
  DQS4_B_C  = M_C_CPU1_SB_DQS_DN<4>
  DQS4_B_T  = M_C_CPU1_SB_DQS_DP<4>
  VSS104  = GND
  CB2_B  = M_C_CPU1_SB_CB<2>
  VSS105  = GND
  CB3_B  = M_C_CPU1_SB_CB<3>
  VSS106  = GND
  DQ2_B  = M_C_CPU1_SB_DQ<2>
  VSS107  = GND
  DQ3_B  = M_C_CPU1_SB_DQ<3>
  VSS108  = GND
  \dqs5_b_c||tdqs5_b_c\  = M_C_CPU1_SB_DQS_DN<5>
  \dqs5_b_t||tdqs5_b_t\  = M_C_CPU1_SB_DQS_DP<5>
  VSS109  = GND
  DQ6_B  = M_C_CPU1_SB_DQ<6>
  VSS110  = GND
  DQ7_B  = M_C_CPU1_SB_DQ<7>
  VSS111  = GND
  DQ10_B  = M_C_CPU1_SB_DQ<10>
  VSS112  = GND
  DQ11_B  = M_C_CPU1_SB_DQ<11>
  VSS113  = GND
  \dqs6_b_c||tdqs6_b_c\  = M_C_CPU1_SB_DQS_DN<6>
  \dqs6_b_t||tdqs6_b_t\  = M_C_CPU1_SB_DQS_DP<6>
  VSS114  = GND
  DQ14_B  = M_C_CPU1_SB_DQ<14>
  VSS115  = GND
  DQ15_B  = M_C_CPU1_SB_DQ<15>
  VSS116  = GND
  DQ18_B  = M_C_CPU1_SB_DQ<18>
  VSS117  = GND
  DQ19_B  = M_C_CPU1_SB_DQ<19>
  VSS118  = GND
  \dqs7_b_c||tdqs7_b_c\  = M_C_CPU1_SB_DQS_DN<7>
  \dqs7_b_t||tdqs7_b_t\  = M_C_CPU1_SB_DQS_DP<7>
  VSS119  = GND
  DQ22_B  = M_C_CPU1_SB_DQ<22>
  VSS120  = GND
  DQ23_B  = M_C_CPU1_SB_DQ<23>
  VSS121  = GND
  DQ26_B  = M_C_CPU1_SB_DQ<26>
  VSS122  = GND
  DQ27_B  = M_C_CPU1_SB_DQ<27>
  VSS123  = GND
  \dqs8_b_c||tdqs8_b_c\  = M_C_CPU1_SB_DQS_DN<8>
  \dqs8_b_t||tdqs8_b_t\  = M_C_CPU1_SB_DQS_DP<8>
  VSS124  = GND
  DQ30_B  = M_C_CPU1_SB_DQ<30>
  VSS125  = GND
  DQ31_B  = M_C_CPU1_SB_DQ<31>
  VSS126  = GND
  G1  = GND
  G2  = GND
  G3  = GND

(kicad_pcb
	(version 20260206)
	(generator "pcbnew")
	(generator_version "10.0")
	(general
		(thickness 1.6)
		(legacy_teardrops no)
	)
	(paper "A4")
	(title_block
		(title "03242023_DA0F0TMBIJ0_F0T_Motherboard_J_brd_V01_OCP.brd")
		(comment 1 "Grand Teton / footprint 663 of 6105 (J21), pads 46-91 of 291")
	)
	(layers
		(0 "F.Cu" signal "TOP")
		(4 "In1.Cu" signal "GND")
		(6 "In2.Cu" signal "IN1")
		(8 "In3.Cu" signal "GND1")
		(10 "In4.Cu" signal "IN2")
		(12 "In5.Cu" signal "GND2")
		(14 "In6.Cu" signal "IN3")
		(16 "In7.Cu" signal "GND3")
		(18 "In8.Cu" signal "VCC")
		(20 "In9.Cu" signal "VCC1")
		(22 "In10.Cu" signal "GND4")
		(24 "In11.Cu" signal "IN4")
		(26 "In12.Cu" signal "GND5")
		(28 "In13.Cu" signal "IN5")
		(30 "In14.Cu" signal "GND6")
		(32 "In15.Cu" signal "IN6")
		(34 "In16.Cu" signal "GND7")
		(2 "B.Cu" signal "BOTTOM")
		(9 "F.Adhes" user "F.Adhesive")
		(11 "B.Adhes" user "B.Adhesive")
		(13 "F.Paste" user "Package Geometry/Pastemask Top")
		(15 "B.Paste" user "Package Geometry/Pastemask Bottom")
		(5 "F.SilkS" user "Ref Des/Silkscreen Top")
		(7 "B.SilkS" user "Ref Des/Silkscreen Bottom")
		(1 "F.Mask" user "Board Geometry/Soldermask Top")
		(3 "B.Mask" user "Board Geometry/Soldermask Bottom")
		(17 "Dwgs.User" user "User.Drawings")
		(19 "Cmts.User" user "User.Comments")
		(21 "Eco1.User" user "User.Eco1")
		(23 "Eco2.User" user "User.Eco2")
		(25 "Edge.Cuts" user "Board Geometry/Outline")
		(27 "Margin" user)
		(31 "F.CrtYd" user "Package Geometry/Place Bound Top")
		(29 "B.CrtYd" user "Package Geometry/Place Bound Bottom")
		(35 "F.Fab" user "Ref Des/Assembly Top")
		(33 "B.Fab" user "Ref Des/Assembly Bottom")
	)
	(footprint ""
		(layer "F.Cu")
		(at 25.27808 -258.091686)
		(property "Reference" "J21"
			(at -0.325882 -81.821274 0)
			(unlocked yes)
			(layer "F.SilkS")
			(effects
				(font
					(size 0.7874 0.5842)
					(thickness 0.1524)
				)
				(justify left)
			)
		)
		(property "Value" ""
			(at 0 0 0)
			(layer "F.Fab")
			(effects
				(font
					(size 1.27 1.27)
				)
			)
		)
		(duplicate_pad_numbers_are_jumpers no)
		(pad "46" smd rect
			(at -2.050034 -25.07488 270)
			(size 0.519938 1.4986)
			(layers "F.Cu" "F.Mask" "F.Paste")
			(net "GND")
		)
		(pad "47" smd rect
			(at -2.050034 -24.224996 270)
			(size 0.519938 1.4986)
			(layers "F.Cu" "F.Mask" "F.Paste")
			(net "M_C_CPU1_SA_DQ<28>")
		)
		(pad "48" smd rect
			(at -2.050034 -23.375112 270)
			(size 0.519938 1.4986)
			(layers "F.Cu" "F.Mask" "F.Paste")
			(net "GND")
		)
		(pad "49" smd rect
			(at -2.050034 -22.524974 270)
			(size 0.519938 1.4986)
			(layers "F.Cu" "F.Mask" "F.Paste")
			(net "M_C_CPU1_SA_DQ<29>")
		)
		(pad "50" smd rect
			(at -2.050034 -21.67509 270)
			(size 0.519938 1.4986)
			(layers "F.Cu" "F.Mask" "F.Paste")
			(net "GND")
		)
		(pad "51" smd rect
			(at -2.050034 -20.824952 270)
			(size 0.519938 1.4986)
			(layers "F.Cu" "F.Mask" "F.Paste")
			(net "M_C_CPU1_SA_CB<0>")
		)
		(pad "52" smd rect
			(at -2.050034 -19.975068 270)
			(size 0.519938 1.4986)
			(layers "F.Cu" "F.Mask" "F.Paste")
			(net "GND")
		)
		(pad "53" smd rect
			(at -2.050034 -19.12493 270)
			(size 0.519938 1.4986)
			(layers "F.Cu" "F.Mask" "F.Paste")
			(net "M_C_CPU1_SA_CB<1>")
		)
		(pad "54" smd rect
			(at -2.050034 -18.275046 270)
			(size 0.519938 1.4986)
			(layers "F.Cu" "F.Mask" "F.Paste")
			(net "GND")
		)
		(pad "55" smd rect
			(at -2.050034 -17.424908 270)
			(size 0.519938 1.4986)
			(layers "F.Cu" "F.Mask" "F.Paste")
			(net "M_C_CPU1_SA_DQS_DP<4>")
		)
		(pad "56" smd rect
			(at -2.050034 -16.575024 270)
			(size 0.519938 1.4986)
			(layers "F.Cu" "F.Mask" "F.Paste")
			(net "M_C_CPU1_SA_DQS_DN<4>")
		)
		(pad "57" smd rect
			(at -2.050034 -15.724886 270)
			(size 0.519938 1.4986)
			(layers "F.Cu" "F.Mask" "F.Paste")
			(net "GND")
		)
		(pad "58" smd rect
			(at -2.050034 -14.875002 270)
			(size 0.519938 1.4986)
			(layers "F.Cu" "F.Mask" "F.Paste")
			(net "M_C_CPU1_SA_CB<4>")
		)
		(pad "59" smd rect
			(at -2.050034 -14.025118 270)
			(size 0.519938 1.4986)
			(layers "F.Cu" "F.Mask" "F.Paste")
			(net "GND")
		)
		(pad "60" smd rect
			(at -2.050034 -13.17498 270)
			(size 0.519938 1.4986)
			(layers "F.Cu" "F.Mask" "F.Paste")
			(net "M_C_CPU1_SA_CB<5>")
		)
		(pad "61" smd rect
			(at -2.050034 -12.325096 270)
			(size 0.519938 1.4986)
			(layers "F.Cu" "F.Mask" "F.Paste")
			(net "GND")
		)
		(pad "62" smd rect
			(at -2.050034 -11.474958 270)
			(size 0.519938 1.4986)
			(layers "F.Cu" "F.Mask" "F.Paste")
			(net "M_C_CPU1_ALERT_N")
		)
		(pad "63" smd rect
			(at -2.050034 -10.625074 270)
			(size 0.519938 1.4986)
			(layers "F.Cu" "F.Mask" "F.Paste")
			(net "GND")
		)
		(pad "64" smd rect
			(at -2.050034 -9.774936 270)
			(size 0.519938 1.4986)
			(layers "F.Cu" "F.Mask" "F.Paste")
			(net "M_C_CPU1_SA_CS_N<0>")
		)
		(pad "65" smd rect
			(at -2.050034 -8.925052 270)
			(size 0.519938 1.4986)
			(layers "F.Cu" "F.Mask" "F.Paste")
			(net "GND")
		)
		(pad "66" smd rect
			(at -2.050034 -8.074914 270)
			(size 0.519938 1.4986)
			(layers "F.Cu" "F.Mask" "F.Paste")
			(net "M_C_CPU1_SA_CA<0>")
		)
		(pad "67" smd rect
			(at -2.050034 -7.22503 270)
			(size 0.519938 1.4986)
			(layers "F.Cu" "F.Mask" "F.Paste")
			(net "GND")
		)
		(pad "68" smd rect
			(at -2.050034 -6.374892 270)
			(size 0.519938 1.4986)
			(layers "F.Cu" "F.Mask" "F.Paste")
			(net "M_C_CPU1_SA_CA<2>")
		)
		(pad "69" smd rect
			(at -2.050034 -5.525008 270)
			(size 0.519938 1.4986)
			(layers "F.Cu" "F.Mask" "F.Paste")
			(net "GND")
		)
		(pad "70" smd rect
			(at -2.050034 -4.675124 270)
			(size 0.519938 1.4986)
			(layers "F.Cu" "F.Mask" "F.Paste")
			(net "M_C_CPU1_SA_CA<4>")
		)
		(pad "71" smd rect
			(at -2.050034 -3.824986 270)
			(size 0.519938 1.4986)
			(layers "F.Cu" "F.Mask" "F.Paste")
			(net "GND")
		)
		(pad "72" smd rect
			(at -2.050034 -2.975102 270)
			(size 0.519938 1.4986)
			(layers "F.Cu" "F.Mask" "F.Paste")
			(net "M_C_CPU1_SA_CA<6>")
		)
		(pad "73" smd rect
			(at -2.050034 -2.124964 270)
			(size 0.519938 1.4986)
			(layers "F.Cu" "F.Mask" "F.Paste")
			(net "GND")
		)
		(pad "74" smd rect
			(at -2.050034 -1.27508 270)
			(size 0.519938 1.4986)
			(layers "F.Cu" "F.Mask" "F.Paste")
			(net "M_C_CPU1_SA_PAR")
		)
		(pad "75" smd rect
			(at -2.050034 -0.424942 270)
			(size 0.519938 1.4986)
			(layers "F.Cu" "F.Mask" "F.Paste")
			(net "GND")
		)
		(pad "76" smd rect
			(at -2.050034 5.525008 270)
			(size 0.519938 1.4986)
			(layers "F.Cu" "F.Mask" "F.Paste")
			(net "M_C_CPU1_SB_CA<0>")
		)
		(pad "77" smd rect
			(at -2.050034 6.374892 270)
			(size 0.519938 1.4986)
			(layers "F.Cu" "F.Mask" "F.Paste")
			(net "GND")
		)
		(pad "78" smd rect
			(at -2.050034 7.22503 270)
			(size 0.519938 1.4986)
			(layers "F.Cu" "F.Mask" "F.Paste")
			(net "M_C_CPU1_SB_CA<2>")
		)
		(pad "79" smd rect
			(at -2.050034 8.074914 270)
			(size 0.519938 1.4986)
			(layers "F.Cu" "F.Mask" "F.Paste")
			(net "GND")
		)
		(pad "80" smd rect
			(at -2.050034 8.925052 270)
			(size 0.519938 1.4986)
			(layers "F.Cu" "F.Mask" "F.Paste")
			(net "M_C_CPU1_SB_CA<4>")
		)
		(pad "81" smd rect
			(at -2.050034 9.774936 270)
			(size 0.519938 1.4986)
			(layers "F.Cu" "F.Mask" "F.Paste")
			(net "GND")
		)
		(pad "82" smd rect
			(at -2.050034 10.625074 270)
			(size 0.519938 1.4986)
			(layers "F.Cu" "F.Mask" "F.Paste")
			(net "M_C_CPU1_SB_CA<6>")
		)
		(pad "83" smd rect
			(at -2.050034 11.474958 270)
			(size 0.519938 1.4986)
			(layers "F.Cu" "F.Mask" "F.Paste")
			(net "GND")
		)
		(pad "84" smd rect
			(at -2.050034 12.325096 270)
			(size 0.519938 1.4986)
			(layers "F.Cu" "F.Mask" "F.Paste")
			(net "M_C_CPU1_SB_CS_N<0>")
		)
		(pad "85" smd rect
			(at -2.050034 13.17498 270)
			(size 0.519938 1.4986)
			(layers "F.Cu" "F.Mask" "F.Paste")
			(net "GND")
		)
		(pad "86" smd rect
			(at -2.050034 14.025118 270)
			(size 0.519938 1.4986)
			(layers "F.Cu" "F.Mask" "F.Paste")
			(net "M_C_CPU1_SA_RSP<0>")
		)
		(pad "87" smd rect
			(at -2.050034 14.875002 270)
			(size 0.519938 1.4986)
			(layers "F.Cu" "F.Mask" "F.Paste")
			(net "M_C_CPU1_SB_RSP<0>")
		)
		(pad "88" smd rect
			(at -2.050034 15.724886 270)
			(size 0.519938 1.4986)
			(layers "F.Cu" "F.Mask" "F.Paste")
			(net "GND")
		)
		(pad "89" smd rect
			(at -2.050034 16.575024 270)
			(size 0.519938 1.4986)
			(layers "F.Cu" "F.Mask" "F.Paste")
			(net "M_C_CPU1_SB_CB<4>")
		)
		(pad "90" smd rect
			(at -2.050034 17.424908 270)
			(size 0.519938 1.4986)
			(layers "F.Cu" "F.Mask" "F.Paste")
			(net "GND")
		)
		(pad "91" smd rect
			(at -2.050034 18.275046 270)
			(size 0.519938 1.4986)
			(layers "F.Cu" "F.Mask" "F.Paste")
			(net "M_C_CPU1_SB_CB<5>")
		)
	)
)
